#ISCELL
  mstr_misc dns *
  *
#ISCELL
  pure_quanta quanta_title_block_c *
  *
#ISCELL
  standard offpage *
  page190_i1
#ISCELL
  pure_quanta_power universal_gnd *
  page190_i10
#CELL
  pure_quanta q_cap *
  page190_i11
#CELL
  pure_quanta q_res *
  page190_i12
#ISCELL
  pure_quanta_power vcc_core *
  page190_i13
#CELL
  pure_quanta q_cap *
  page190_i14
#ISCELL
  pure_quanta_power universal_gnd *
  page190_i15
#ISCELL
  standard offpage *
  page190_i16
#CELL
  pure_quanta isl99390frztr5935 *
  page190_i17
#ISCELL
  pure_quanta_power universal_gnd *
  page190_i18
#ISCELL
  pure_quanta_power universal_gnd *
  page190_i19
#ISCELL
  standard offpage *
  page190_i2
#CELL
  pure_quanta q_cap *
  page190_i20
#CELL
  pure_quanta q_res *
  page190_i21
#CELL
  pure_quanta q_cap *
  page190_i22
#ISCELL
  pure_quanta_power universal_gnd *
  page190_i23
#CELL
  pure_quanta q_res *
  page190_i24
#CELL
  pure_quanta q_cap *
  page190_i25
#CELL
  pure_quanta q_cap *
  page190_i26
#CELL
  pure_quanta q_cap *
  page190_i27
#ISCELL
  pure_quanta_power universal_gnd *
  page190_i28
#CELL
  pure_quanta q_res *
  page190_i29
#ISCELL
  pure_quanta_power universal_gnd *
  page190_i3
#CELL
  pure_quanta q_res *
  page190_i30
#ISCELL
  pure_quanta_power universal_gnd *
  page190_i31
#CELL
  pure_quanta q_cap *
  page190_i32
#ISCELL
  pure_quanta_power universal_gnd *
  page190_i33
#ISCELL
  standard offpage *
  page190_i34
#CELL
  pure_quanta q_res *
  page190_i35
#CELL
  pure_quanta q_cap *
  page190_i36
#ISCELL
  pure_quanta_power universal_gnd *
  page190_i37
#ISCELL
  standard offpage *
  page190_i38
#CELL
  pure_quanta q_res *
  page190_i39
#CELL
  pure_quanta q_cap *
  page190_i4
#ISCELL
  pure_quanta_power universal_gnd *
  page190_i40
#CELL
  pure_quanta q_cap *
  page190_i41
#ISCELL
  pure_quanta_power vcc_core *
  page190_i42
#CELL
  pure_quanta q_cap *
  page190_i43
#CELL
  pure_quanta q_cap *
  page190_i44
#CELL
  pure_quanta q_cap *
  page190_i45
#CELL
  pure_quanta q_res *
  page190_i46
#ISCELL
  standard offpage *
  page190_i47
#CELL
  pure_quanta q_cap *
  page190_i48
#CELL
  pure_quanta q_cap *
  page190_i49
#ISCELL
  pure_quanta_power universal_gnd *
  page190_i5
#CELL
  pure_quanta q_cap *
  page190_i50
#ISCELL
  standard offpage *
  page190_i51
#CELL
  pure_quanta q_inductor4p_14 *
  page190_i52
#ISCELL
  standard offpage *
  page190_i53
#CELL
  pure_quanta q_cap *
  page190_i54
#ISCELL
  pure_quanta_power universal_gnd *
  page190_i55
#CELL
  pure_quanta q_cap *
  page190_i56
#CELL
  pure_quanta q_cap *
  page190_i57
#ISCELL
  pure_quanta_power vcc_core *
  page190_i58
#CELL
  pure_quanta q_capp *
  page190_i59
#ISCELL
  standard offpage *
  page190_i6
#CELL
  pure_quanta q_cap *
  page190_i60
#ISCELL
  pure_quanta_power universal_gnd *
  page190_i61
#CELL
  pure_quanta q_cap *
  page190_i62
#CELL
  pure_quanta q_capp *
  page190_i63
#ISCELL
  pure_quanta_power vcc_core *
  page190_i64
#ISCELL
  pure_quanta_power universal_gnd *
  page190_i65
#CELL
  pure_quanta q_capp *
  page190_i66
#ISCELL
  pure_quanta_power vcc_core *
  page190_i67
#CELL
  pure_quanta q_cap *
  page190_i68
#CELL
  pure_quanta q_inductor4p_14 *
  page190_i69
#ISCELL
  standard offpage *
  page190_i7
#ISCELL
  pure_quanta_power universal_gnd *
  page190_i70
#CELL
  pure_quanta q_cap *
  page190_i71
#ISCELL
  pure_quanta_power vcc_core *
  page190_i72
#CELL
  pure_quanta q_capp *
  page190_i73
#CELL
  pure_quanta q_inductor *
  page190_i74
#ISCELL
  pure_quanta_power universal_gnd *
  page190_i75
#ISCELL
  pure_quanta_power universal_gnd *
  page190_i76
#CELL
  pure_quanta q_cap *
  page190_i77
#ISCELL
  pure_quanta_power vcc_core *
  page190_i78
#CELL
  pure_quanta q_cap *
  page190_i79
#CELL
  pure_quanta q_res *
  page190_i8
#CELL
  pure_quanta q_cap *
  page190_i80
#CELL
  pure_quanta q_cap *
  page190_i81
#ISCELL
  pure_quanta_power universal_gnd *
  page190_i82
#CELL
  pure_quanta q_res *
  page190_i83
#ISCELL
  pure_quanta_power vcc_core *
  page190_i84
#CELL
  pure_quanta q_res *
  page190_i85
#CELL
  pure_quanta isl99390frztr5935 *
  page190_i86
#CELL
  pure_quanta q_cap *
  page190_i87
#CELL
  pure_quanta q_cap *
  page190_i88
#ISCELL
  standard offpage *
  page190_i9
